# TIMECARD (Time Appliance Project (Time Card)) — schematic netlist excerpt (pin names and nets, part order shuffled) for the footprints in the layout excerpt that follows; sources: Cadence DE-HDL packaged netlist, KiCad conversion of R4006-B0001-02_R01.brd

R23  RESISTOR  0OHM -  pkg SMC_0402R_H016  page 9 : \1\ = CARD_PRESENT ; \2\ = UNNAMED_3_CONN64PGF_I61_PRSNT22
R161  RESISTOR  4.7KOHM 1%  pkg SMC_0402R_H016  page 16 : \1\ = UNNAMED_5_24LC16BTISTTSSOP8_I_1 ; \2\ = SG

(kicad_pcb
	(version 20260206)
	(generator "pcbnew")
	(generator_version "10.0")
	(general
		(thickness 1.6)
		(legacy_teardrops no)
	)
	(paper "A4")
	(title_block
		(title "timecard-production-celestica-r4006 — R4006-B0001-02_R01.brd")
		(comment 1 "Time Appliance Project (Time Card) / footprints 984-985 of 1113")
	)
	(layers
		(0 "F.Cu" signal "TOP")
		(4 "In1.Cu" signal "L02_GND1")
		(6 "In2.Cu" signal "L03_SIG1")
		(8 "In3.Cu" signal "L04_GND2")
		(10 "In4.Cu" signal "L05_VCC1")
		(12 "In5.Cu" signal "L06_VCC2")
		(14 "In6.Cu" signal "L07_GND3")
		(16 "In7.Cu" signal "L08_SIG2")
		(18 "In8.Cu" signal "L09_GND4")
		(2 "B.Cu" signal "BOTTOM")
		(9 "F.Adhes" user "F.Adhesive")
		(11 "B.Adhes" user "B.Adhesive")
		(13 "F.Paste" user "Package Geometry/Pastemask Top")
		(15 "B.Paste" user "Package Geometry/Pastemask Bottom")
		(5 "F.SilkS" user "Ref Des/Silkscreen Top")
		(7 "B.SilkS" user "Ref Des/Silkscreen Bottom")
		(1 "F.Mask" user "Board Geometry/Soldermask Top")
		(3 "B.Mask" user "Board Geometry/Soldermask Bottom")
		(17 "Dwgs.User" user "User.Drawings")
		(19 "Cmts.User" user "User.Comments")
		(21 "Eco1.User" user "User.Eco1")
		(23 "Eco2.User" user "User.Eco2")
		(25 "Edge.Cuts" user "Board Geometry/Outline")
		(27 "Margin" user)
		(31 "F.CrtYd" user "Package Geometry/Place Bound Top")
		(29 "B.CrtYd" user "Package Geometry/Place Bound Bottom")
		(35 "F.Fab" user "Ref Des/Assembly Top")
		(33 "B.Fab" user "Ref Des/Assembly Bottom")
	)
	(footprint ""
		(layer "B.Cu")
		(at 47.36084 -15.82928 -90)
		(property "Reference" "R23"
			(at -2.45872 0.02921 270)
			(unlocked yes)
			(layer "B.SilkS")
			(effects
				(font
					(size 0.7874 0.5842)
					(thickness 0.1524)
				)
				(justify mirror)
			)
		)
		(property "Value" "VAL*"
			(at -0.02032 2.13233 270)
			(unlocked yes)
			(layer "B.Fab")
			(hide yes)
			(effects
				(font
					(size 0.7874 0.5842)
					(thickness 0.1524)
				)
				(justify mirror)
			)
		)
		(property "Device Type" "RESISTOR-G155-100R0-J0,0OHM,-"
			(at -0.008382 1.210564 270)
			(unlocked yes)
			(layer "B.Fab")
			(hide yes)
			(effects
				(font
					(size 0.7874 0.5842)
					(thickness 0.1524)
				)
				(justify mirror)
			)
		)
		(property "User Part Number" "PARTNUM*"
			(at -0.02032 4.024884 270)
			(unlocked yes)
			(layer "Cmts.User")
			(hide yes)
			(effects
				(font
					(size 0.7874 0.5842)
					(thickness 0.1524)
				)
				(justify mirror)
			)
		)
		(property "Tolerance" "TOL*"
			(at -0.044704 3.05435 270)
			(unlocked yes)
			(layer "Cmts.User")
			(hide yes)
			(effects
				(font
					(size 0.7874 0.5842)
					(thickness 0.1524)
				)
				(justify mirror)
			)
		)
		(duplicate_pad_numbers_are_jumpers no)
		(fp_line
			(start -1.143 0.5588)
			(end -1.143 -0.5588)
			(stroke
				(width 0.1)
				(type default)
			)
			(layer "B.SilkS")
		)
		(fp_line
			(start 1.143 0.5588)
			(end -1.143 0.5588)
			(stroke
				(width 0.1)
				(type default)
			)
			(layer "B.SilkS")
		)
		(fp_line
			(start -1.143 -0.5588)
			(end 1.143 -0.5588)
			(stroke
				(width 0.1)
				(type default)
			)
			(layer "B.SilkS")
		)
		(fp_line
			(start 1.143 -0.5588)
			(end 1.143 0.5588)
			(stroke
				(width 0.1)
				(type default)
			)
			(layer "B.SilkS")
		)
		(fp_rect
			(start 1.143 -0.5588)
			(end -1.143 0.5588)
			(stroke
				(width 0)
				(type default)
			)
			(fill no)
			(layer "B.CrtYd")
		)
		(fp_line
			(start -0.508 0.3048)
			(end -0.508 -0.3048)
			(stroke
				(width 0.1)
				(type default)
			)
			(layer "B.Fab")
		)
		(fp_line
			(start 0.508 0.3048)
			(end -0.508 0.3048)
			(stroke
				(width 0.1)
				(type default)
			)
			(layer "B.Fab")
		)
		(fp_line
			(start -0.508 -0.3048)
			(end 0.508 -0.3048)
			(stroke
				(width 0.1)
				(type default)
			)
			(layer "B.Fab")
		)
		(fp_line
			(start 0.508 -0.3048)
			(end 0.508 0.3048)
			(stroke
				(width 0.1)
				(type default)
			)
			(layer "B.Fab")
		)
		(pad "1" smd rect
			(at 0.5334 0 90)
			(size 0.7112 0.6096)
			(layers "B.Cu" "B.Mask" "B.Paste")
			(net "CARD_PRESENT")
		)
		(pad "2" smd rect
			(at -0.5334 0 90)
			(size 0.7112 0.6096)
			(layers "B.Cu" "B.Mask" "B.Paste")
			(net "UNNAMED_3_CONN64PGF_I61_PRSNT22")
		)
		(zone
			(layer "B.Cu")
			(hatch none 0.5)
			(connect_pads
				(clearance 0)
			)
			(min_thickness 0.25)
			(keepout
				(tracks allowed)
				(vias not_allowed)
				(pads allowed)
				(copperpour not_allowed)
				(footprints allowed)
			)
			(placement
				(enabled no)
				(sheetname "")
			)
			(fill
				(thermal_gap 0.5)
				(thermal_bridge_width 0.5)
				(island_removal_mode 0)
			)
			(polygon
				(pts
					(xy 47.66564 -15.75308) (xy 47.66564 -15.90548) (xy 47.05604 -15.90548) (xy 47.05604 -15.75308)
				)
			)
		)
	)
	(footprint ""
		(layer "B.Cu")
		(at 21.1582 -23.6728 90)
		(property "Reference" "R161"
			(at 3.8862 0.13843 270)
			(unlocked yes)
			(layer "B.SilkS")
			(effects
				(font
					(size 0.7874 0.5842)
					(thickness 0.1524)
				)
				(justify mirror)
			)
		)
		(property "Value" "VAL*"
			(at -0.02032 2.13233 90)
			(unlocked yes)
			(layer "B.Fab")
			(hide yes)
			(effects
				(font
					(size 0.7874 0.5842)
					(thickness 0.1524)
				)
				(justify mirror)
			)
		)
		(property "Tolerance" "TOL*"
			(at -0.044704 3.05435 90)
			(unlocked yes)
			(layer "Cmts.User")
			(hide yes)
			(effects
				(font
					(size 0.7874 0.5842)
					(thickness 0.1524)
				)
				(justify mirror)
			)
		)
		(property "User Part Number" "PARTNUM*"
			(at -0.02032 4.024884 90)
			(unlocked yes)
			(layer "Cmts.User")
			(hide yes)
			(effects
				(font
					(size 0.7874 0.5842)
					(thickness 0.1524)
				)
				(justify mirror)
			)
		)
		(property "Device Type" "RESISTOR-G155-14701-01,4.7KOHMA"
			(at -0.008382 1.210564 90)
			(unlocked yes)
			(layer "B.Fab")
			(hide yes)
			(effects
				(font
					(size 0.7874 0.5842)
					(thickness 0.1524)
				)
				(justify mirror)
			)
		)
		(duplicate_pad_numbers_are_jumpers no)
		(fp_line
			(start 1.143 -0.5588)
			(end 1.143 0.5588)
			(stroke
				(width 0.1)
				(type default)
			)
			(layer "B.SilkS")
		)
		(fp_line
			(start -1.143 -0.5588)
			(end 1.143 -0.5588)
			(stroke
				(width 0.1)
				(type default)
			)
			(layer "B.SilkS")
		)
		(fp_line
			(start 1.143 0.5588)
			(end -1.143 0.5588)
			(stroke
				(width 0.1)
				(type default)
			)
			(layer "B.SilkS")
		)
		(fp_line
			(start -1.143 0.5588)
			(end -1.143 -0.5588)
			(stroke
				(width 0.1)
				(type default)
			)
			(layer "B.SilkS")
		)
		(fp_poly
			(pts
				(xy 1.143 0.5588) (xy -1.143 0.5588) (xy -1.143 -0.5588) (xy 1.143 -0.5588)
			)
			(stroke
				(width 0)
				(type default)
			)
			(fill no)
			(layer "B.CrtYd")
		)
		(fp_line
			(start 0.508 -0.3048)
			(end 0.508 0.3048)
			(stroke
				(width 0.1)
				(type default)
			)
			(layer "B.Fab")
		)
		(fp_line
			(start -0.508 -0.3048)
			(end 0.508 -0.3048)
			(stroke
				(width 0.1)
				(type default)
			)
			(layer "B.Fab")
		)
		(fp_line
			(start 0.508 0.3048)
			(end -0.508 0.3048)
			(stroke
				(width 0.1)
				(type default)
			)
			(layer "B.Fab")
		)
		(fp_line
			(start -0.508 0.3048)
			(end -0.508 -0.3048)
			(stroke
				(width 0.1)
				(type default)
			)
			(layer "B.Fab")
		)
		(pad "1" smd rect
			(at 0.5334 0 270)
			(size 0.7112 0.6096)
			(layers "B.Cu" "B.Mask" "B.Paste")
			(net "UNNAMED_5_24LC16BTISTTSSOP8_I_1")
		)
		(pad "2" smd rect
			(at -0.5334 0 270)
			(size 0.7112 0.6096)
			(layers "B.Cu" "B.Mask" "B.Paste")
			(net "SG")
		)
		(zone
			(layer "B.Cu")
			(hatch none 0.5)
			(connect_pads
				(clearance 0)
			)
			(min_thickness 0.25)
			(keepout
				(tracks allowed)
				(vias not_allowed)
				(pads allowed)
				(copperpour not_allowed)
				(footprints allowed)
			)
			(placement
				(enabled no)
				(sheetname "")
			)
			(fill
				(thermal_gap 0.5)
				(thermal_bridge_width 0.5)
				(island_removal_mode 0)
			)
			(polygon
				(pts
					(xy 21.463 -23.749) (xy 20.8534 -23.749) (xy 20.8534 -23.5966) (xy 21.463 -23.5966)
				)
			)
		)
		(zone
			(layer "B.Cu")
			(hatch none 0.5)
			(connect_pads
				(clearance 0)
			)
			(min_thickness 0.25)
			(keepout
				(tracks not_allowed)
				(vias allowed)
				(pads allowed)
				(copperpour not_allowed)
				(footprints allowed)
			)
			(placement
				(enabled no)
				(sheetname "")
			)
			(fill
				(thermal_gap 0.5)
				(thermal_bridge_width 0.5)
				(island_removal_mode 0)
			)
			(polygon
				(pts
					(xy 21.463 -23.749) (xy 20.8534 -23.749) (xy 20.8534 -23.5966) (xy 21.463 -23.5966)
				)
			)
		)
	)
)
